(kicad_pcb
	(version 20260206)
	(generator "pcbnew")
	(generator_version "10.0")
	(general
		(thickness 1.6)
		(legacy_teardrops no)
	)
	(paper "A4")
	(title_block
		(title "04192023_DAF0TMB3IC0_F0TG_MB_C_brd_V02_OCP.brd")
		(comment 1 "Grand Teton / footprints 6159-6165 of 8354")
	)
	(layers
		(0 "F.Cu" signal "TOP")
		(4 "In1.Cu" signal "GND")
		(6 "In2.Cu" signal "IN1")
		(8 "In3.Cu" signal "GND1")
		(10 "In4.Cu" signal "IN2")
		(12 "In5.Cu" signal "GND2")
		(14 "In6.Cu" signal "IN3")
		(16 "In7.Cu" signal "GND3")
		(18 "In8.Cu" signal "VCC")
		(20 "In9.Cu" signal "VCC1")
		(22 "In10.Cu" signal "GND4")
		(24 "In11.Cu" signal "IN4")
		(26 "In12.Cu" signal "GND5")
		(28 "In13.Cu" signal "IN5")
		(30 "In14.Cu" signal "GND6")
		(32 "In15.Cu" signal "IN6")
		(34 "In16.Cu" signal "GND7")
		(2 "B.Cu" signal "BOTTOM")
		(9 "F.Adhes" user "F.Adhesive")
		(11 "B.Adhes" user "B.Adhesive")
		(13 "F.Paste" user "Package Geometry/Pastemask Top")
		(15 "B.Paste" user "Package Geometry/Pastemask Bottom")
		(5 "F.SilkS" user "Ref Des/Silkscreen Top")
		(7 "B.SilkS" user "Ref Des/Silkscreen Bottom")
		(1 "F.Mask" user "Board Geometry/Soldermask Top")
		(3 "B.Mask" user "Board Geometry/Soldermask Bottom")
		(17 "Dwgs.User" user "User.Drawings")
		(19 "Cmts.User" user "User.Comments")
		(21 "Eco1.User" user "User.Eco1")
		(23 "Eco2.User" user "User.Eco2")
		(25 "Edge.Cuts" user "Board Geometry/Outline")
		(27 "Margin" user)
		(31 "F.CrtYd" user "Package Geometry/Place Bound Top")
		(29 "B.CrtYd" user "Package Geometry/Place Bound Bottom")
		(35 "F.Fab" user "Ref Des/Assembly Top")
		(33 "B.Fab" user "Ref Des/Assembly Bottom")
	)
	(footprint ""
		(layer "B.Cu")
		(at 156.154374 -322.805552)
		(property "Reference" "R559"
			(at 0 0 0)
			(layer "B.SilkS")
			(hide yes)
			(effects
				(font
					(size 1.27 1.27)
				)
				(justify mirror)
			)
		)
		(property "Value" ""
			(at 0 0 0)
			(layer "B.Fab")
			(effects
				(font
					(size 1.27 1.27)
				)
				(justify mirror)
			)
		)
		(duplicate_pad_numbers_are_jumpers no)
		(fp_line
			(start -0.7874 -0.4064)
			(end -0.7874 0.4064)
			(stroke
				(width 0.1524)
				(type default)
			)
			(layer "B.SilkS")
		)
		(fp_line
			(start -0.7874 0.4064)
			(end 0.7874 0.4064)
			(stroke
				(width 0.1524)
				(type default)
			)
			(layer "B.SilkS")
		)
		(fp_line
			(start 0.7874 -0.4064)
			(end -0.7874 -0.4064)
			(stroke
				(width 0.1524)
				(type default)
			)
			(layer "B.SilkS")
		)
		(fp_line
			(start 0.7874 0.4064)
			(end 0.7874 -0.4064)
			(stroke
				(width 0.1524)
				(type default)
			)
			(layer "B.SilkS")
		)
		(fp_line
			(start -0.67945 -0.3048)
			(end -0.67945 0.3048)
			(stroke
				(width 0.1)
				(type default)
			)
			(layer "B.Fab")
		)
		(fp_line
			(start -0.67945 0.3048)
			(end -0.120396 0.3048)
			(stroke
				(width 0.1)
				(type default)
			)
			(layer "B.Fab")
		)
		(fp_line
			(start -0.12065 -0.3048)
			(end -0.67945 -0.3048)
			(stroke
				(width 0.1)
				(type default)
			)
			(layer "B.Fab")
		)
		(fp_line
			(start -0.12065 -0.2794)
			(end -0.12065 -0.3048)
			(stroke
				(width 0.1)
				(type default)
			)
			(layer "B.Fab")
		)
		(fp_line
			(start -0.120396 0.2794)
			(end 0.12065 0.2794)
			(stroke
				(width 0.1)
				(type default)
			)
			(layer "B.Fab")
		)
		(fp_line
			(start -0.120396 0.3048)
			(end -0.120396 0.2794)
			(stroke
				(width 0.1)
				(type default)
			)
			(layer "B.Fab")
		)
		(fp_line
			(start 0.12065 -0.305054)
			(end 0.12065 -0.2794)
			(stroke
				(width 0.1)
				(type default)
			)
			(layer "B.Fab")
		)
		(fp_line
			(start 0.12065 -0.2794)
			(end -0.12065 -0.2794)
			(stroke
				(width 0.1)
				(type default)
			)
			(layer "B.Fab")
		)
		(fp_line
			(start 0.12065 0.2794)
			(end 0.12065 0.3048)
			(stroke
				(width 0.1)
				(type default)
			)
			(layer "B.Fab")
		)
		(fp_line
			(start 0.12065 0.3048)
			(end 0.67945 0.3048)
			(stroke
				(width 0.1)
				(type default)
			)
			(layer "B.Fab")
		)
		(fp_line
			(start 0.67945 -0.305054)
			(end 0.12065 -0.305054)
			(stroke
				(width 0.1)
				(type default)
			)
			(layer "B.Fab")
		)
		(fp_line
			(start 0.67945 0.3048)
			(end 0.67945 -0.305054)
			(stroke
				(width 0.1)
				(type default)
			)
			(layer "B.Fab")
		)
		(pad "1" smd circle
			(at 0.40005 0 180)
			(size 0 0)
			(layers "B.Cu" "B.Mask" "B.Paste")
			(net "PVDD18_S5_P1")
		)
		(pad "2" smd circle
			(at -0.40005 0 180)
			(size 0 0)
			(layers "B.Cu" "B.Mask" "B.Paste")
			(net "RST_CPU1_SYS_N")
		)
	)
	(footprint ""
		(layer "B.Cu")
		(at 419.806374 -395.148562 90)
		(property "Reference" "C975"
			(at 0 0 90)
			(layer "B.SilkS")
			(hide yes)
			(effects
				(font
					(size 1.27 1.27)
				)
				(justify mirror)
			)
		)
		(property "Value" ""
			(at 0 0 90)
			(layer "B.Fab")
			(effects
				(font
					(size 1.27 1.27)
				)
				(justify mirror)
			)
		)
		(duplicate_pad_numbers_are_jumpers no)
		(fp_line
			(start 0.299974 -0.150114)
			(end -0.299974 -0.150114)
			(stroke
				(width 0.1)
				(type default)
			)
			(layer "B.Fab")
		)
		(fp_line
			(start -0.299974 -0.150114)
			(end -0.299974 0.150114)
			(stroke
				(width 0.1)
				(type default)
			)
			(layer "B.Fab")
		)
		(fp_line
			(start 0.299974 0.150114)
			(end 0.299974 -0.150114)
			(stroke
				(width 0.1)
				(type default)
			)
			(layer "B.Fab")
		)
		(fp_line
			(start -0.299974 0.150114)
			(end 0.299974 0.150114)
			(stroke
				(width 0.1)
				(type default)
			)
			(layer "B.Fab")
		)
		(pad "1" smd rect
			(at 0.2667 0 270)
			(size 0.3048 0.381)
			(layers "B.Cu" "B.Mask" "B.Paste")
			(net "P0V9_CPU0_RT2_2A")
		)
		(pad "2" smd rect
			(at -0.2667 0 270)
			(size 0.3048 0.381)
			(layers "B.Cu" "B.Mask" "B.Paste")
			(net "GND")
		)
	)
	(footprint ""
		(layer "B.Cu")
		(at 90.503502 -205.14945 90)
		(property "Reference" "R539"
			(at 0 0 90)
			(layer "B.SilkS")
			(hide yes)
			(effects
				(font
					(size 1.27 1.27)
				)
				(justify mirror)
			)
		)
		(property "Value" ""
			(at 0 0 90)
			(layer "B.Fab")
			(effects
				(font
					(size 1.27 1.27)
				)
				(justify mirror)
			)
		)
		(duplicate_pad_numbers_are_jumpers no)
		(fp_line
			(start 0.7874 -0.4064)
			(end -0.7874 -0.4064)
			(stroke
				(width 0.1524)
				(type default)
			)
			(layer "B.SilkS")
		)
		(fp_line
			(start -0.7874 -0.4064)
			(end -0.7874 0.4064)
			(stroke
				(width 0.1524)
				(type default)
			)
			(layer "B.SilkS")
		)
		(fp_line
			(start 0.7874 0.4064)
			(end 0.7874 -0.4064)
			(stroke
				(width 0.1524)
				(type default)
			)
			(layer "B.SilkS")
		)
		(fp_line
			(start -0.7874 0.4064)
			(end 0.7874 0.4064)
			(stroke
				(width 0.1524)
				(type default)
			)
			(layer "B.SilkS")
		)
		(fp_line
			(start 0.67945 -0.305054)
			(end 0.12065 -0.305054)
			(stroke
				(width 0.1)
				(type default)
			)
			(layer "B.Fab")
		)
		(fp_line
			(start 0.12065 -0.305054)
			(end 0.12065 -0.2794)
			(stroke
				(width 0.1)
				(type default)
			)
			(layer "B.Fab")
		)
		(fp_line
			(start -0.12065 -0.3048)
			(end -0.67945 -0.3048)
			(stroke
				(width 0.1)
				(type default)
			)
			(layer "B.Fab")
		)
		(fp_line
			(start -0.67945 -0.3048)
			(end -0.67945 0.3048)
			(stroke
				(width 0.1)
				(type default)
			)
			(layer "B.Fab")
		)
		(fp_line
			(start 0.12065 -0.2794)
			(end -0.12065 -0.2794)
			(stroke
				(width 0.1)
				(type default)
			)
			(layer "B.Fab")
		)
		(fp_line
			(start -0.12065 -0.2794)
			(end -0.12065 -0.3048)
			(stroke
				(width 0.1)
				(type default)
			)
			(layer "B.Fab")
		)
		(fp_line
			(start 0.12065 0.2794)
			(end 0.12065 0.3048)
			(stroke
				(width 0.1)
				(type default)
			)
			(layer "B.Fab")
		)
		(fp_line
			(start -0.120396 0.2794)
			(end 0.12065 0.2794)
			(stroke
				(width 0.1)
				(type default)
			)
			(layer "B.Fab")
		)
		(fp_line
			(start 0.67945 0.3048)
			(end 0.67945 -0.305054)
			(stroke
				(width 0.1)
				(type default)
			)
			(layer "B.Fab")
		)
		(fp_line
			(start 0.12065 0.3048)
			(end 0.67945 0.3048)
			(stroke
				(width 0.1)
				(type default)
			)
			(layer "B.Fab")
		)
		(fp_line
			(start -0.120396 0.3048)
			(end -0.120396 0.2794)
			(stroke
				(width 0.1)
				(type default)
			)
			(layer "B.Fab")
		)
		(fp_line
			(start -0.67945 0.3048)
			(end -0.120396 0.3048)
			(stroke
				(width 0.1)
				(type default)
			)
			(layer "B.Fab")
		)
		(pad "1" smd circle
			(at 0.40005 0 270)
			(size 0 0)
			(layers "B.Cu" "B.Mask" "B.Paste")
			(net "CPU1_XTRIG_L6")
		)
		(pad "2" smd circle
			(at -0.40005 0 270)
			(size 0 0)
			(layers "B.Cu" "B.Mask" "B.Paste")
			(net "PVDD18_S5_P1")
		)
	)
	(footprint ""
		(layer "B.Cu")
		(at 51.766978 -429.84293 -90)
		(property "Reference" "R3473"
			(at 0 0 90)
			(layer "B.SilkS")
			(hide yes)
			(effects
				(font
					(size 1.27 1.27)
				)
				(justify mirror)
			)
		)
		(property "Value" ""
			(at 0 0 90)
			(layer "B.Fab")
			(effects
				(font
					(size 1.27 1.27)
				)
				(justify mirror)
			)
		)
		(duplicate_pad_numbers_are_jumpers no)
		(fp_line
			(start -0.7874 0.4064)
			(end 0.7874 0.4064)
			(stroke
				(width 0.1524)
				(type default)
			)
			(layer "B.SilkS")
		)
		(fp_line
			(start 0.7874 0.4064)
			(end 0.7874 -0.4064)
			(stroke
				(width 0.1524)
				(type default)
			)
			(layer "B.SilkS")
		)
		(fp_line
			(start -0.7874 -0.4064)
			(end -0.7874 0.4064)
			(stroke
				(width 0.1524)
				(type default)
			)
			(layer "B.SilkS")
		)
		(fp_line
			(start 0.7874 -0.4064)
			(end -0.7874 -0.4064)
			(stroke
				(width 0.1524)
				(type default)
			)
			(layer "B.SilkS")
		)
		(fp_line
			(start -0.67945 0.3048)
			(end -0.120396 0.3048)
			(stroke
				(width 0.1)
				(type default)
			)
			(layer "B.Fab")
		)
		(fp_line
			(start -0.120396 0.3048)
			(end -0.120396 0.2794)
			(stroke
				(width 0.1)
				(type default)
			)
			(layer "B.Fab")
		)
		(fp_line
			(start 0.12065 0.3048)
			(end 0.67945 0.3048)
			(stroke
				(width 0.1)
				(type default)
			)
			(layer "B.Fab")
		)
		(fp_line
			(start 0.67945 0.3048)
			(end 0.67945 -0.305054)
			(stroke
				(width 0.1)
				(type default)
			)
			(layer "B.Fab")
		)
		(fp_line
			(start -0.120396 0.2794)
			(end 0.12065 0.2794)
			(stroke
				(width 0.1)
				(type default)
			)
			(layer "B.Fab")
		)
		(fp_line
			(start 0.12065 0.2794)
			(end 0.12065 0.3048)
			(stroke
				(width 0.1)
				(type default)
			)
			(layer "B.Fab")
		)
		(fp_line
			(start -0.12065 -0.2794)
			(end -0.12065 -0.3048)
			(stroke
				(width 0.1)
				(type default)
			)
			(layer "B.Fab")
		)
		(fp_line
			(start 0.12065 -0.2794)
			(end -0.12065 -0.2794)
			(stroke
				(width 0.1)
				(type default)
			)
			(layer "B.Fab")
		)
		(fp_line
			(start -0.67945 -0.3048)
			(end -0.67945 0.3048)
			(stroke
				(width 0.1)
				(type default)
			)
			(layer "B.Fab")
		)
		(fp_line
			(start -0.12065 -0.3048)
			(end -0.67945 -0.3048)
			(stroke
				(width 0.1)
				(type default)
			)
			(layer "B.Fab")
		)
		(fp_line
			(start 0.12065 -0.305054)
			(end 0.12065 -0.2794)
			(stroke
				(width 0.1)
				(type default)
			)
			(layer "B.Fab")
		)
		(fp_line
			(start 0.67945 -0.305054)
			(end 0.12065 -0.305054)
			(stroke
				(width 0.1)
				(type default)
			)
			(layer "B.Fab")
		)
		(pad "1" smd circle
			(at 0.40005 0 90)
			(size 0 0)
			(layers "B.Cu" "B.Mask" "B.Paste")
			(net "GPU_PRSNT_N")
		)
		(pad "2" smd circle
			(at -0.40005 0 90)
			(size 0 0)
			(layers "B.Cu" "B.Mask" "B.Paste")
			(net "GND")
		)
	)
	(footprint ""
		(layer "B.Cu")
		(at 130.09118 -390.560052 90)
		(property "Reference" "C501"
			(at 0 0 90)
			(layer "B.SilkS")
			(hide yes)
			(effects
				(font
					(size 1.27 1.27)
				)
				(justify mirror)
			)
		)
		(property "Value" ""
			(at 0 0 90)
			(layer "B.Fab")
			(effects
				(font
					(size 1.27 1.27)
				)
				(justify mirror)
			)
		)
		(duplicate_pad_numbers_are_jumpers no)
		(fp_line
			(start 0.7874 -0.4064)
			(end -0.7874 -0.4064)
			(stroke
				(width 0.1524)
				(type default)
			)
			(layer "B.SilkS")
		)
		(fp_line
			(start -0.7874 -0.4064)
			(end -0.7874 0.4064)
			(stroke
				(width 0.1524)
				(type default)
			)
			(layer "B.SilkS")
		)
		(fp_line
			(start 0.7874 0.4064)
			(end 0.7874 -0.4064)
			(stroke
				(width 0.1524)
				(type default)
			)
			(layer "B.SilkS")
		)
		(fp_line
			(start -0.7874 0.4064)
			(end 0.7874 0.4064)
			(stroke
				(width 0.1524)
				(type default)
			)
			(layer "B.SilkS")
		)
		(fp_line
			(start 0.67945 -0.305054)
			(end 0.12065 -0.305054)
			(stroke
				(width 0.1)
				(type default)
			)
			(layer "B.Fab")
		)
		(fp_line
			(start 0.12065 -0.305054)
			(end 0.12065 -0.2794)
			(stroke
				(width 0.1)
				(type default)
			)
			(layer "B.Fab")
		)
		(fp_line
			(start -0.12065 -0.3048)
			(end -0.67945 -0.3048)
			(stroke
				(width 0.1)
				(type default)
			)
			(layer "B.Fab")
		)
		(fp_line
			(start -0.67945 -0.3048)
			(end -0.67945 0.3048)
			(stroke
				(width 0.1)
				(type default)
			)
			(layer "B.Fab")
		)
		(fp_line
			(start 0.12065 -0.2794)
			(end -0.12065 -0.2794)
			(stroke
				(width 0.1)
				(type default)
			)
			(layer "B.Fab")
		)
		(fp_line
			(start -0.12065 -0.2794)
			(end -0.12065 -0.3048)
			(stroke
				(width 0.1)
				(type default)
			)
			(layer "B.Fab")
		)
		(fp_line
			(start 0.12065 0.2794)
			(end 0.12065 0.3048)
			(stroke
				(width 0.1)
				(type default)
			)
			(layer "B.Fab")
		)
		(fp_line
			(start -0.120396 0.2794)
			(end 0.12065 0.2794)
			(stroke
				(width 0.1)
				(type default)
			)
			(layer "B.Fab")
		)
		(fp_line
			(start 0.67945 0.3048)
			(end 0.67945 -0.305054)
			(stroke
				(width 0.1)
				(type default)
			)
			(layer "B.Fab")
		)
		(fp_line
			(start 0.12065 0.3048)
			(end 0.67945 0.3048)
			(stroke
				(width 0.1)
				(type default)
			)
			(layer "B.Fab")
		)
		(fp_line
			(start -0.120396 0.3048)
			(end -0.120396 0.2794)
			(stroke
				(width 0.1)
				(type default)
			)
			(layer "B.Fab")
		)
		(fp_line
			(start -0.67945 0.3048)
			(end -0.120396 0.3048)
			(stroke
				(width 0.1)
				(type default)
			)
			(layer "B.Fab")
		)
		(pad "1" smd circle
			(at 0.40005 0 270)
			(size 0 0)
			(layers "B.Cu" "B.Mask" "B.Paste")
			(net "P0V9_CPU1_RT3_2A")
		)
		(pad "2" smd circle
			(at -0.40005 0 270)
			(size 0 0)
			(layers "B.Cu" "B.Mask" "B.Paste")
			(net "GND")
		)
	)
	(footprint ""
		(layer "B.Cu")
		(at 383.076958 -205.101952 -90)
		(property "Reference" "R429"
			(at 0 0 90)
			(layer "B.SilkS")
			(hide yes)
			(effects
				(font
					(size 1.27 1.27)
				)
				(justify mirror)
			)
		)
		(property "Value" ""
			(at 0 0 90)
			(layer "B.Fab")
			(effects
				(font
					(size 1.27 1.27)
				)
				(justify mirror)
			)
		)
		(duplicate_pad_numbers_are_jumpers no)
		(fp_line
			(start -0.7874 0.4064)
			(end 0.7874 0.4064)
			(stroke
				(width 0.1524)
				(type default)
			)
			(layer "B.SilkS")
		)
		(fp_line
			(start 0.7874 0.4064)
			(end 0.7874 -0.4064)
			(stroke
				(width 0.1524)
				(type default)
			)
			(layer "B.SilkS")
		)
		(fp_line
			(start -0.7874 -0.4064)
			(end -0.7874 0.4064)
			(stroke
				(width 0.1524)
				(type default)
			)
			(layer "B.SilkS")
		)
		(fp_line
			(start 0.7874 -0.4064)
			(end -0.7874 -0.4064)
			(stroke
				(width 0.1524)
				(type default)
			)
			(layer "B.SilkS")
		)
		(fp_line
			(start -0.67945 0.3048)
			(end -0.120396 0.3048)
			(stroke
				(width 0.1)
				(type default)
			)
			(layer "B.Fab")
		)
		(fp_line
			(start -0.120396 0.3048)
			(end -0.120396 0.2794)
			(stroke
				(width 0.1)
				(type default)
			)
			(layer "B.Fab")
		)
		(fp_line
			(start 0.12065 0.3048)
			(end 0.67945 0.3048)
			(stroke
				(width 0.1)
				(type default)
			)
			(layer "B.Fab")
		)
		(fp_line
			(start 0.67945 0.3048)
			(end 0.67945 -0.305054)
			(stroke
				(width 0.1)
				(type default)
			)
			(layer "B.Fab")
		)
		(fp_line
			(start -0.120396 0.2794)
			(end 0.12065 0.2794)
			(stroke
				(width 0.1)
				(type default)
			)
			(layer "B.Fab")
		)
		(fp_line
			(start 0.12065 0.2794)
			(end 0.12065 0.3048)
			(stroke
				(width 0.1)
				(type default)
			)
			(layer "B.Fab")
		)
		(fp_line
			(start -0.12065 -0.2794)
			(end -0.12065 -0.3048)
			(stroke
				(width 0.1)
				(type default)
			)
			(layer "B.Fab")
		)
		(fp_line
			(start 0.12065 -0.2794)
			(end -0.12065 -0.2794)
			(stroke
				(width 0.1)
				(type default)
			)
			(layer "B.Fab")
		)
		(fp_line
			(start -0.67945 -0.3048)
			(end -0.67945 0.3048)
			(stroke
				(width 0.1)
				(type default)
			)
			(layer "B.Fab")
		)
		(fp_line
			(start -0.12065 -0.3048)
			(end -0.67945 -0.3048)
			(stroke
				(width 0.1)
				(type default)
			)
			(layer "B.Fab")
		)
		(fp_line
			(start 0.12065 -0.305054)
			(end 0.12065 -0.2794)
			(stroke
				(width 0.1)
				(type default)
			)
			(layer "B.Fab")
		)
		(fp_line
			(start 0.67945 -0.305054)
			(end 0.12065 -0.305054)
			(stroke
				(width 0.1)
				(type default)
			)
			(layer "B.Fab")
		)
		(pad "1" smd rect
			(at 0.40005 0 270)
			(size 0.4572 0.508)
			(layers "B.Cu" "B.Mask" "B.Paste")
			(net "I3C_1_SPD_DDRGL_CPU0_SDA")
		)
		(pad "2" smd rect
			(at -0.40005 0 270)
			(size 0.4572 0.508)
			(layers "B.Cu" "B.Mask" "B.Paste")
			(net "I3C_1_SPD_DDRGL_CPU0_R_SDA")
		)
	)
	(footprint ""
		(layer "B.Cu")
		(at 99.480878 -139.93241 90)
		(property "Reference" "PC251"
			(at 0 0 90)
			(layer "B.SilkS")
			(hide yes)
			(effects
				(font
					(size 1.27 1.27)
				)
				(justify mirror)
			)
		)
		(property "Value" ""
			(at 0 0 90)
			(layer "B.Fab")
			(effects
				(font
					(size 1.27 1.27)
				)
				(justify mirror)
			)
		)
		(duplicate_pad_numbers_are_jumpers no)
		(fp_line
			(start 0.7874 -0.4064)
			(end -0.7874 -0.4064)
			(stroke
				(width 0.1524)
				(type default)
			)
			(layer "B.SilkS")
		)
		(fp_line
			(start -0.7874 -0.4064)
			(end -0.7874 0.4064)
			(stroke
				(width 0.1524)
				(type default)
			)
			(layer "B.SilkS")
		)
		(fp_line
			(start 0.7874 0.4064)
			(end 0.7874 -0.4064)
			(stroke
				(width 0.1524)
				(type default)
			)
			(layer "B.SilkS")
		)
		(fp_line
			(start -0.7874 0.4064)
			(end 0.7874 0.4064)
			(stroke
				(width 0.1524)
				(type default)
			)
			(layer "B.SilkS")
		)
		(fp_line
			(start 0.67945 -0.305054)
			(end 0.12065 -0.305054)
			(stroke
				(width 0.1)
				(type default)
			)
			(layer "B.Fab")
		)
		(fp_line
			(start 0.12065 -0.305054)
			(end 0.12065 -0.2794)
			(stroke
				(width 0.1)
				(type default)
			)
			(layer "B.Fab")
		)
		(fp_line
			(start -0.12065 -0.3048)
			(end -0.67945 -0.3048)
			(stroke
				(width 0.1)
				(type default)
			)
			(layer "B.Fab")
		)
		(fp_line
			(start -0.67945 -0.3048)
			(end -0.67945 0.3048)
			(stroke
				(width 0.1)
				(type default)
			)
			(layer "B.Fab")
		)
		(fp_line
			(start 0.12065 -0.2794)
			(end -0.12065 -0.2794)
			(stroke
				(width 0.1)
				(type default)
			)
			(layer "B.Fab")
		)
		(fp_line
			(start -0.12065 -0.2794)
			(end -0.12065 -0.3048)
			(stroke
				(width 0.1)
				(type default)
			)
			(layer "B.Fab")
		)
		(fp_line
			(start 0.12065 0.2794)
			(end 0.12065 0.3048)
			(stroke
				(width 0.1)
				(type default)
			)
			(layer "B.Fab")
		)
		(fp_line
			(start -0.120396 0.2794)
			(end 0.12065 0.2794)
			(stroke
				(width 0.1)
				(type default)
			)
			(layer "B.Fab")
		)
		(fp_line
			(start 0.67945 0.3048)
			(end 0.67945 -0.305054)
			(stroke
				(width 0.1)
				(type default)
			)
			(layer "B.Fab")
		)
		(fp_line
			(start 0.12065 0.3048)
			(end 0.67945 0.3048)
			(stroke
				(width 0.1)
				(type default)
			)
			(layer "B.Fab")
		)
		(fp_line
			(start -0.120396 0.3048)
			(end -0.120396 0.2794)
			(stroke
				(width 0.1)
				(type default)
			)
			(layer "B.Fab")
		)
		(fp_line
			(start -0.67945 0.3048)
			(end -0.120396 0.3048)
			(stroke
				(width 0.1)
				(type default)
			)
			(layer "B.Fab")
		)
		(pad "1" smd circle
			(at 0.40005 0 270)
			(size 0 0)
			(layers "B.Cu" "B.Mask" "B.Paste")
			(net "PVDDCR_CPU0_P1_VCCS")
		)
		(pad "2" smd circle
			(at -0.40005 0 270)
			(size 0 0)
			(layers "B.Cu" "B.Mask" "B.Paste")
			(net "GND")
		)
	)
)
